(kicad_pcb
	(version 20260206)
	(generator "pcbnew")
	(generator_version "10.0")
	(general
		(thickness 1.6)
		(legacy_teardrops no)
	)
	(paper "A4")
	(title_block
		(title "Bryce Canyon_R.DPB_16317-1_OCP.brd")
		(comment 1 "Bryce Canyon / footprints 1188-1195 of 2099")
	)
	(layers
		(0 "F.Cu" signal "TOP")
		(4 "In1.Cu" signal "L2GND")
		(6 "In2.Cu" signal "L3")
		(8 "In3.Cu" signal "L4VCC")
		(10 "In4.Cu" signal "L5VCC")
		(12 "In5.Cu" signal "L6")
		(14 "In6.Cu" signal "L7GND")
		(2 "B.Cu" signal "BOTTOM")
		(9 "F.Adhes" user "F.Adhesive")
		(11 "B.Adhes" user "B.Adhesive")
		(13 "F.Paste" user "Package Geometry/Pastemask Top")
		(15 "B.Paste" user "Package Geometry/Pastemask Bottom")
		(5 "F.SilkS" user "Ref Des/Silkscreen Top")
		(7 "B.SilkS" user "Ref Des/Silkscreen Bottom")
		(1 "F.Mask" user "Board Geometry/Soldermask Top")
		(3 "B.Mask" user "Board Geometry/Soldermask Bottom")
		(17 "Dwgs.User" user "User.Drawings")
		(19 "Cmts.User" user "User.Comments")
		(21 "Eco1.User" user "User.Eco1")
		(23 "Eco2.User" user "User.Eco2")
		(25 "Edge.Cuts" user "Board Geometry/Outline")
		(27 "Margin" user)
		(31 "F.CrtYd" user "Package Geometry/Place Bound Top")
		(29 "B.CrtYd" user "Package Geometry/Place Bound Bottom")
		(35 "F.Fab" user "Ref Des/Assembly Top")
		(33 "B.Fab" user "Ref Des/Assembly Bottom")
	)
	(footprint ""
		(layer "F.Cu")
		(at 141.097 -24.511 -90)
		(property "Reference" "R729"
			(at 0 0 270)
			(layer "F.SilkS")
			(hide yes)
			(effects
				(font
					(size 1.27 1.27)
				)
			)
		)
		(property "Value" "300KR2F-GP"
			(at 0.064008 -3.993896 270)
			(unlocked yes)
			(layer "F.Fab")
			(hide yes)
			(effects
				(font
					(size 1.016 1.016)
					(thickness 0.1524)
				)
			)
		)
		(property "Device Type" "R402H16"
			(at 0.064008 -5.517896 270)
			(unlocked yes)
			(layer "F.Fab")
			(hide yes)
			(effects
				(font
					(size 1.016 1.016)
					(thickness 0.1524)
				)
			)
		)
		(duplicate_pad_numbers_are_jumpers no)
		(fp_line
			(start -0.508 -0.9398)
			(end -0.508 0.9398)
			(stroke
				(width 0.1524)
				(type default)
			)
			(layer "F.SilkS")
		)
		(fp_line
			(start 0.508 -0.9398)
			(end -0.508 -0.9398)
			(stroke
				(width 0.1524)
				(type default)
			)
			(layer "F.SilkS")
		)
		(fp_rect
			(start -0.508 0.9398)
			(end 0.508 -0.9398)
			(stroke
				(width 0)
				(type default)
			)
			(fill no)
			(layer "F.CrtYd")
		)
		(fp_rect
			(start -0.508 0.9398)
			(end 0.508 -0.9398)
			(stroke
				(width 0)
				(type default)
			)
			(fill no)
			(layer "F.Fab")
		)
		(pad "1" smd custom
			(at 0 -0.4445 270)
			(size 0.1397 0.1397)
			(layers "F.Cu" "F.Mask" "F.Paste")
			(net "SW_HDD_N28")
			(options
				(clearance outline)
				(anchor circle)
			)
			(primitives
				(gr_poly
					(pts
						(arc
							(start -0.1778 -0.2794)
							(mid -0.249642 -0.249642)
							(end -0.2794 -0.1778)
						)
						(arc
							(start -0.2794 0.1778)
							(mid -0.249642 0.249642)
							(end -0.1778 0.2794)
						)
						(arc
							(start 0.1778 0.2794)
							(mid 0.249642 0.249642)
							(end 0.2794 0.1778)
						)
						(arc
							(start 0.2794 -0.1778)
							(mid 0.249642 -0.249642)
							(end 0.1778 -0.2794)
						)
					)
					(width 0)
					(fill yes)
				)
			)
		)
		(pad "2" smd custom
			(at 0 0.4445 270)
			(size 0.1397 0.1397)
			(layers "F.Cu" "F.Mask" "F.Paste")
			(net "P12V_B")
			(options
				(clearance outline)
				(anchor circle)
			)
			(primitives
				(gr_poly
					(pts
						(arc
							(start -0.1778 -0.2794)
							(mid -0.249642 -0.249642)
							(end -0.2794 -0.1778)
						)
						(arc
							(start -0.2794 0.1778)
							(mid -0.249642 0.249642)
							(end -0.1778 0.2794)
						)
						(arc
							(start 0.1778 0.2794)
							(mid 0.249642 0.249642)
							(end 0.2794 0.1778)
						)
						(arc
							(start 0.2794 -0.1778)
							(mid 0.249642 -0.249642)
							(end 0.1778 -0.2794)
						)
					)
					(width 0)
					(fill yes)
				)
			)
		)
	)
	(footprint ""
		(layer "F.Cu")
		(at 477.536002 -128.627124 180)
		(property "Reference" "VIA47"
			(at 0 0 180)
			(layer "F.SilkS")
			(hide yes)
			(effects
				(font
					(size 1.27 1.27)
				)
			)
		)
		(property "Value" "100OHM-8L-2D36MM-L18-GP"
			(at 3.8989 0.5715 180)
			(unlocked yes)
			(layer "F.Fab")
			(hide yes)
			(effects
				(font
					(size 1.016 1.016)
					(thickness 0.1524)
				)
			)
		)
		(property "Device Type" "VIA-PCIE-4P-414097"
			(at 3.8989 -0.9525 180)
			(unlocked yes)
			(layer "F.Fab")
			(hide yes)
			(effects
				(font
					(size 1.016 1.016)
					(thickness 0.1524)
				)
			)
		)
		(duplicate_pad_numbers_are_jumpers no)
		(fp_rect
			(start -2.0701 0.4826)
			(end 2.0701 -0.4826)
			(stroke
				(width 0)
				(type default)
			)
			(fill no)
			(layer "F.CrtYd")
		)
		(fp_rect
			(start -2.0701 0.4826)
			(end 2.0701 -0.4826)
			(stroke
				(width 0)
				(type default)
			)
			(fill no)
			(layer "F.Fab")
		)
		(pad "1" thru_hole circle
			(at -1.5875 0 180)
			(size 0.508 0.508)
			(drill 0.254)
			(layers "*.Cu" "*.Mask")
			(remove_unused_layers no)
			(net "GND")
			(clearance 0.2286)
			(thermal_gap 0.2286)
		)
		(pad "2" thru_hole circle
			(at -0.5715 0 180)
			(size 0.508 0.508)
			(drill 0.254)
			(layers "*.Cu" "*.Mask")
			(remove_unused_layers no)
			(net "PHY_SCC_B_TO_DRV_B_23_DP")
			(clearance 0.2286)
			(thermal_gap 0.2286)
		)
		(pad "3" thru_hole circle
			(at 0.5715 0 180)
			(size 0.508 0.508)
			(drill 0.254)
			(layers "*.Cu" "*.Mask")
			(remove_unused_layers no)
			(net "PHY_SCC_B_TO_DRV_B_23_DN")
			(clearance 0.2286)
			(thermal_gap 0.2286)
		)
		(pad "4" thru_hole circle
			(at 1.5875 0 180)
			(size 0.508 0.508)
			(drill 0.254)
			(layers "*.Cu" "*.Mask")
			(remove_unused_layers no)
			(net "GND")
			(clearance 0.2286)
			(thermal_gap 0.2286)
		)
	)
	(footprint ""
		(layer "F.Cu")
		(at 428.117 -274.955 180)
		(property "Reference" "C152"
			(at 0 0 180)
			(layer "F.SilkS")
			(hide yes)
			(effects
				(font
					(size 1.27 1.27)
				)
			)
		)
		(property "Value" "SC4D7U25V5KX-1-GP"
			(at -0.0762 -6.1214 180)
			(unlocked yes)
			(layer "F.Fab")
			(hide yes)
			(effects
				(font
					(size 1.016 1.016)
					(thickness 0.1524)
				)
			)
		)
		(property "Device Type" "C805H58"
			(at -0.0762 -8.1534 180)
			(unlocked yes)
			(layer "F.Fab")
			(hide yes)
			(effects
				(font
					(size 1.016 1.016)
					(thickness 0.1524)
				)
			)
		)
		(duplicate_pad_numbers_are_jumpers no)
		(fp_line
			(start 0.635 0)
			(end -0.635 0)
			(stroke
				(width 0.508)
				(type default)
			)
			(layer "F.SilkS")
		)
		(fp_rect
			(start -0.9652 1.778)
			(end 0.9652 -1.778)
			(stroke
				(width 0)
				(type default)
			)
			(fill no)
			(layer "F.CrtYd")
		)
		(fp_poly
			(pts
				(xy -0.9652 -1.778) (xy 0.9652 -1.778) (xy 0.9652 1.778) (xy -0.9652 1.778)
			)
			(stroke
				(width 0)
				(type default)
			)
			(fill no)
			(layer "F.Fab")
		)
		(pad "1" smd rect
			(at 0 -0.9652 180)
			(size 1.397 1.143)
			(layers "F.Cu" "F.Mask" "F.Paste")
			(net "P12V_HDD9")
		)
		(pad "2" smd rect
			(at 0 0.9652 180)
			(size 1.397 1.143)
			(layers "F.Cu" "F.Mask" "F.Paste")
			(net "GND")
		)
	)
	(footprint ""
		(layer "F.Cu")
		(at 97.385632 -14.990826 90)
		(property "Reference" "VIA53"
			(at 0 0 90)
			(layer "F.SilkS")
			(hide yes)
			(effects
				(font
					(size 1.27 1.27)
				)
			)
		)
		(property "Value" "100OHM-8L-2D36MM-L18-GP"
			(at 3.8989 0.5715 90)
			(unlocked yes)
			(layer "F.Fab")
			(hide yes)
			(effects
				(font
					(size 1.016 1.016)
					(thickness 0.1524)
				)
			)
		)
		(property "Device Type" "VIA-PCIE-4P-414097"
			(at 3.8989 -0.9525 90)
			(unlocked yes)
			(layer "F.Fab")
			(hide yes)
			(effects
				(font
					(size 1.016 1.016)
					(thickness 0.1524)
				)
			)
		)
		(duplicate_pad_numbers_are_jumpers no)
		(fp_rect
			(start -2.0701 0.4826)
			(end 2.0701 -0.4826)
			(stroke
				(width 0)
				(type default)
			)
			(fill no)
			(layer "F.CrtYd")
		)
		(fp_rect
			(start -2.0701 0.4826)
			(end 2.0701 -0.4826)
			(stroke
				(width 0)
				(type default)
			)
			(fill no)
			(layer "F.Fab")
		)
		(pad "1" thru_hole circle
			(at -1.5875 0 90)
			(size 0.508 0.508)
			(drill 0.254)
			(layers "*.Cu" "*.Mask")
			(remove_unused_layers no)
			(net "GND")
			(clearance 0.2286)
			(thermal_gap 0.2286)
		)
		(pad "2" thru_hole circle
			(at -0.5715 0 90)
			(size 0.508 0.508)
			(drill 0.254)
			(layers "*.Cu" "*.Mask")
			(remove_unused_layers no)
			(net "PHY_SCC_B_TO_DRV_B_26_DP")
			(clearance 0.2286)
			(thermal_gap 0.2286)
		)
		(pad "3" thru_hole circle
			(at 0.5715 0 90)
			(size 0.508 0.508)
			(drill 0.254)
			(layers "*.Cu" "*.Mask")
			(remove_unused_layers no)
			(net "PHY_SCC_B_TO_DRV_B_26_DN")
			(clearance 0.2286)
			(thermal_gap 0.2286)
		)
		(pad "4" thru_hole circle
			(at 1.5875 0 90)
			(size 0.508 0.508)
			(drill 0.254)
			(layers "*.Cu" "*.Mask")
			(remove_unused_layers no)
			(net "GND")
			(clearance 0.2286)
			(thermal_gap 0.2286)
		)
	)
	(footprint ""
		(layer "F.Cu")
		(at 98.425 -147.066 90)
		(property "Reference" "C218"
			(at 0 0 90)
			(layer "F.SilkS")
			(hide yes)
			(effects
				(font
					(size 1.27 1.27)
				)
			)
		)
		(property "Value" "SCD01U50V2KX-1GP"
			(at 1.1811 -2.7051 90)
			(unlocked yes)
			(layer "F.Fab")
			(hide yes)
			(effects
				(font
					(size 1.016 1.016)
					(thickness 0.1524)
				)
			)
		)
		(property "Device Type" "C402H22"
			(at 1.1811 -4.2291 90)
			(unlocked yes)
			(layer "F.Fab")
			(hide yes)
			(effects
				(font
					(size 1.016 1.016)
					(thickness 0.1524)
				)
			)
		)
		(duplicate_pad_numbers_are_jumpers no)
		(fp_rect
			(start -0.4318 0.9525)
			(end 0.4318 -0.9525)
			(stroke
				(width 0)
				(type default)
			)
			(fill no)
			(layer "F.CrtYd")
		)
		(fp_rect
			(start -0.4318 0.9525)
			(end 0.4318 -0.9525)
			(stroke
				(width 0)
				(type default)
			)
			(fill no)
			(layer "F.Fab")
		)
		(pad "1" smd custom
			(at 0 -0.4445 90)
			(size 0.1524 0.1524)
			(layers "F.Cu" "F.Mask" "F.Paste")
			(net "HDD_PRSNT_14")
			(options
				(clearance outline)
				(anchor circle)
			)
			(primitives
				(gr_poly
					(pts
						(arc
							(start 0.3048 -0.2032)
							(mid 0.275042 -0.275042)
							(end 0.2032 -0.3048)
						)
						(arc
							(start -0.2032 -0.3048)
							(mid -0.275042 -0.275042)
							(end -0.3048 -0.2032)
						)
						(arc
							(start -0.3048 0.2032)
							(mid -0.275042 0.275042)
							(end -0.2032 0.3048)
						)
						(arc
							(start 0.2032 0.3048)
							(mid 0.275042 0.275042)
							(end 0.3048 0.2032)
						)
					)
					(width 0)
					(fill yes)
				)
			)
		)
		(pad "2" smd custom
			(at 0 0.4445 90)
			(size 0.1524 0.1524)
			(layers "F.Cu" "F.Mask" "F.Paste")
			(net "GND")
			(options
				(clearance outline)
				(anchor circle)
			)
			(primitives
				(gr_poly
					(pts
						(arc
							(start 0.3048 -0.2032)
							(mid 0.275042 -0.275042)
							(end 0.2032 -0.3048)
						)
						(arc
							(start -0.2032 -0.3048)
							(mid -0.275042 -0.275042)
							(end -0.3048 -0.2032)
						)
						(arc
							(start -0.3048 0.2032)
							(mid -0.275042 0.275042)
							(end -0.2032 0.3048)
						)
						(arc
							(start 0.2032 0.3048)
							(mid 0.275042 0.275042)
							(end 0.3048 0.2032)
						)
					)
					(width 0)
					(fill yes)
				)
			)
		)
	)
	(footprint ""
		(layer "F.Cu")
		(at 252.333252 -131.428998 -90)
		(property "Reference" "R401"
			(at 0 0 270)
			(layer "F.SilkS")
			(hide yes)
			(effects
				(font
					(size 1.27 1.27)
				)
			)
		)
		(property "Value" "10KR2F-2-GP"
			(at 0.064008 -3.993896 270)
			(unlocked yes)
			(layer "F.Fab")
			(hide yes)
			(effects
				(font
					(size 1.016 1.016)
					(thickness 0.1524)
				)
			)
		)
		(property "Device Type" "R402H16"
			(at 0.064008 -5.517896 270)
			(unlocked yes)
			(layer "F.Fab")
			(hide yes)
			(effects
				(font
					(size 1.016 1.016)
					(thickness 0.1524)
				)
			)
		)
		(duplicate_pad_numbers_are_jumpers no)
		(fp_line
			(start -0.508 -0.9398)
			(end -0.508 0.9398)
			(stroke
				(width 0.1524)
				(type default)
			)
			(layer "F.SilkS")
		)
		(fp_line
			(start 0.508 -0.9398)
			(end -0.508 -0.9398)
			(stroke
				(width 0.1524)
				(type default)
			)
			(layer "F.SilkS")
		)
		(fp_rect
			(start -0.508 0.9398)
			(end 0.508 -0.9398)
			(stroke
				(width 0)
				(type default)
			)
			(fill no)
			(layer "F.CrtYd")
		)
		(fp_rect
			(start -0.508 0.9398)
			(end 0.508 -0.9398)
			(stroke
				(width 0)
				(type default)
			)
			(fill no)
			(layer "F.Fab")
		)
		(pad "1" smd custom
			(at 0 -0.4445 270)
			(size 0.1397 0.1397)
			(layers "F.Cu" "F.Mask" "F.Paste")
			(net "P3V3_STBY_B")
			(options
				(clearance outline)
				(anchor circle)
			)
			(primitives
				(gr_poly
					(pts
						(arc
							(start -0.1778 -0.2794)
							(mid -0.249642 -0.249642)
							(end -0.2794 -0.1778)
						)
						(arc
							(start -0.2794 0.1778)
							(mid -0.249642 0.249642)
							(end -0.1778 0.2794)
						)
						(arc
							(start 0.1778 0.2794)
							(mid 0.249642 0.249642)
							(end 0.2794 0.1778)
						)
						(arc
							(start 0.2794 -0.1778)
							(mid 0.249642 -0.249642)
							(end 0.1778 -0.2794)
						)
					)
					(width 0)
					(fill yes)
				)
			)
		)
		(pad "2" smd custom
			(at 0 0.4445 270)
			(size 0.1397 0.1397)
			(layers "F.Cu" "F.Mask" "F.Paste")
			(net "I2C_DPB_BUFF_READY")
			(options
				(clearance outline)
				(anchor circle)
			)
			(primitives
				(gr_poly
					(pts
						(arc
							(start -0.1778 -0.2794)
							(mid -0.249642 -0.249642)
							(end -0.2794 -0.1778)
						)
						(arc
							(start -0.2794 0.1778)
							(mid -0.249642 0.249642)
							(end -0.1778 0.2794)
						)
						(arc
							(start 0.1778 0.2794)
							(mid 0.249642 0.249642)
							(end 0.2794 0.1778)
						)
						(arc
							(start 0.2794 -0.1778)
							(mid 0.249642 -0.249642)
							(end 0.1778 -0.2794)
						)
					)
					(width 0)
					(fill yes)
				)
			)
		)
	)
	(footprint ""
		(layer "F.Cu")
		(at 192.035684 -14.990826 90)
		(property "Reference" "VIA59"
			(at 0 0 90)
			(layer "F.SilkS")
			(hide yes)
			(effects
				(font
					(size 1.27 1.27)
				)
			)
		)
		(property "Value" "100OHM-8L-2D36MM-L18-GP"
			(at 3.8989 0.5715 90)
			(unlocked yes)
			(layer "F.Fab")
			(hide yes)
			(effects
				(font
					(size 1.016 1.016)
					(thickness 0.1524)
				)
			)
		)
		(property "Device Type" "VIA-PCIE-4P-414097"
			(at 3.8989 -0.9525 90)
			(unlocked yes)
			(layer "F.Fab")
			(hide yes)
			(effects
				(font
					(size 1.016 1.016)
					(thickness 0.1524)
				)
			)
		)
		(duplicate_pad_numbers_are_jumpers no)
		(fp_rect
			(start -2.0701 0.4826)
			(end 2.0701 -0.4826)
			(stroke
				(width 0)
				(type default)
			)
			(fill no)
			(layer "F.CrtYd")
		)
		(fp_rect
			(start -2.0701 0.4826)
			(end 2.0701 -0.4826)
			(stroke
				(width 0)
				(type default)
			)
			(fill no)
			(layer "F.Fab")
		)
		(pad "1" thru_hole circle
			(at -1.5875 0 90)
			(size 0.508 0.508)
			(drill 0.254)
			(layers "*.Cu" "*.Mask")
			(remove_unused_layers no)
			(net "GND")
			(clearance 0.2286)
			(thermal_gap 0.2286)
		)
		(pad "2" thru_hole circle
			(at -0.5715 0 90)
			(size 0.508 0.508)
			(drill 0.254)
			(layers "*.Cu" "*.Mask")
			(remove_unused_layers no)
			(net "PHY_SCC_B_TO_DRV_B_29_DP")
			(clearance 0.2286)
			(thermal_gap 0.2286)
		)
		(pad "3" thru_hole circle
			(at 0.5715 0 90)
			(size 0.508 0.508)
			(drill 0.254)
			(layers "*.Cu" "*.Mask")
			(remove_unused_layers no)
			(net "PHY_SCC_B_TO_DRV_B_29_DN")
			(clearance 0.2286)
			(thermal_gap 0.2286)
		)
		(pad "4" thru_hole circle
			(at 1.5875 0 90)
			(size 0.508 0.508)
			(drill 0.254)
			(layers "*.Cu" "*.Mask")
			(remove_unused_layers no)
			(net "GND")
			(clearance 0.2286)
			(thermal_gap 0.2286)
		)
	)
	(footprint ""
		(layer "F.Cu")
		(at 191.135 -150.114 180)
		(property "Reference" "R465"
			(at 0 0 180)
			(layer "F.SilkS")
			(hide yes)
			(effects
				(font
					(size 1.27 1.27)
				)
			)
		)
		(property "Value" "220R3F-1-GP"
			(at -0.0254 -2.5146 180)
			(unlocked yes)
			(layer "F.Fab")
			(hide yes)
			(effects
				(font
					(size 1.016 1.016)
					(thickness 0.1524)
				)
			)
		)
		(property "Device Type" "R603H22"
			(at -0.0254 -4.0386 180)
			(unlocked yes)
			(layer "F.Fab")
			(hide yes)
			(effects
				(font
					(size 1.016 1.016)
					(thickness 0.1524)
				)
			)
		)
		(duplicate_pad_numbers_are_jumpers no)
		(fp_line
			(start 0.2032 0)
			(end 0.4826 0)
			(stroke
				(width 0.2032)
				(type default)
			)
			(layer "F.SilkS")
		)
		(fp_line
			(start -0.4826 0)
			(end -0.2032 0)
			(stroke
				(width 0.2032)
				(type default)
			)
			(layer "F.SilkS")
		)
		(fp_rect
			(start -0.5842 1.3335)
			(end 0.5842 -1.3335)
			(stroke
				(width 0)
				(type default)
			)
			(fill no)
			(layer "F.CrtYd")
		)
		(fp_rect
			(start -0.5842 1.3335)
			(end 0.5842 -1.3335)
			(stroke
				(width 0)
				(type default)
			)
			(fill no)
			(layer "F.Fab")
		)
		(pad "1" smd custom
			(at 0 -0.762 180)
			(size 0.2159 0.2159)
			(layers "F.Cu" "F.Mask" "F.Paste")
			(net "HDD_PRSNT_17")
			(options
				(clearance outline)
				(anchor circle)
			)
			(primitives
				(gr_poly
					(pts
						(arc
							(start -0.3302 -0.4318)
							(mid -0.402042 -0.402042)
							(end -0.4318 -0.3302)
						)
						(arc
							(start -0.4318 0.3302)
							(mid -0.402042 0.402042)
							(end -0.3302 0.4318)
						)
						(arc
							(start 0.3302 0.4318)
							(mid 0.402042 0.402042)
							(end 0.4318 0.3302)
						)
						(arc
							(start 0.4318 -0.3302)
							(mid 0.402042 -0.402042)
							(end 0.3302 -0.4318)
						)
					)
					(width 0)
					(fill yes)
				)
			)
		)
		(pad "2" smd custom
			(at 0 0.762 180)
			(size 0.2159 0.2159)
			(layers "F.Cu" "F.Mask" "F.Paste")
			(net "DRIVE_B_17_INS")
			(options
				(clearance outline)
				(anchor circle)
			)
			(primitives
				(gr_poly
					(pts
						(arc
							(start -0.3302 -0.4318)
							(mid -0.402042 -0.402042)
							(end -0.4318 -0.3302)
						)
						(arc
							(start -0.4318 0.3302)
							(mid -0.402042 0.402042)
							(end -0.3302 0.4318)
						)
						(arc
							(start 0.3302 0.4318)
							(mid 0.402042 0.402042)
							(end 0.4318 0.3302)
						)
						(arc
							(start 0.4318 -0.3302)
							(mid 0.402042 -0.402042)
							(end 0.3302 -0.4318)
						)
					)
					(width 0)
					(fill yes)
				)
			)
		)
	)
)
